# S9S_MB_2U (Grand Teton) — schematic netlist excerpt (pin names and nets, part order shuffled) for the footprints in the layout excerpt that follows; sources: Cadence DE-HDL packaged netlist, KiCad conversion of 03242023_DA0F0TMBIJ0_F0T_Motherboard_J_brd_V01_OCP.brd

R3232  Q_RES  100K 1% CHIP  pkg 0402LF  page 154 : A = RST_HP_OCP_SFF_R_N ; B = GND
R3690  Q_RES  4.7K 1% EMPTY  pkg 0402LF  page 250 : A = ADC128_VREF ; B = GND

(kicad_pcb
	(version 20260206)
	(generator "pcbnew")
	(generator_version "10.0")
	(general
		(thickness 1.6)
		(legacy_teardrops no)
	)
	(paper "A4")
	(title_block
		(title "03242023_DA0F0TMBIJ0_F0T_Motherboard_J_brd_V01_OCP.brd")
		(comment 1 "Grand Teton / footprints 2808-2809 of 6105")
	)
	(layers
		(0 "F.Cu" signal "TOP")
		(4 "In1.Cu" signal "GND")
		(6 "In2.Cu" signal "IN1")
		(8 "In3.Cu" signal "GND1")
		(10 "In4.Cu" signal "IN2")
		(12 "In5.Cu" signal "GND2")
		(14 "In6.Cu" signal "IN3")
		(16 "In7.Cu" signal "GND3")
		(18 "In8.Cu" signal "VCC")
		(20 "In9.Cu" signal "VCC1")
		(22 "In10.Cu" signal "GND4")
		(24 "In11.Cu" signal "IN4")
		(26 "In12.Cu" signal "GND5")
		(28 "In13.Cu" signal "IN5")
		(30 "In14.Cu" signal "GND6")
		(32 "In15.Cu" signal "IN6")
		(34 "In16.Cu" signal "GND7")
		(2 "B.Cu" signal "BOTTOM")
		(9 "F.Adhes" user "F.Adhesive")
		(11 "B.Adhes" user "B.Adhesive")
		(13 "F.Paste" user "Package Geometry/Pastemask Top")
		(15 "B.Paste" user "Package Geometry/Pastemask Bottom")
		(5 "F.SilkS" user "Ref Des/Silkscreen Top")
		(7 "B.SilkS" user "Ref Des/Silkscreen Bottom")
		(1 "F.Mask" user "Board Geometry/Soldermask Top")
		(3 "B.Mask" user "Board Geometry/Soldermask Bottom")
		(17 "Dwgs.User" user "User.Drawings")
		(19 "Cmts.User" user "User.Comments")
		(21 "Eco1.User" user "User.Eco1")
		(23 "Eco2.User" user "User.Eco2")
		(25 "Edge.Cuts" user "Board Geometry/Outline")
		(27 "Margin" user)
		(31 "F.CrtYd" user "Package Geometry/Place Bound Top")
		(29 "B.CrtYd" user "Package Geometry/Place Bound Bottom")
		(35 "F.Fab" user "Ref Des/Assembly Top")
		(33 "B.Fab" user "Ref Des/Assembly Bottom")
	)
	(footprint ""
		(layer "F.Cu")
		(at 22.809454 -114.431826 180)
		(property "Reference" "R3690"
			(at 0 0 180)
			(layer "F.SilkS")
			(hide yes)
			(effects
				(font
					(size 1.27 1.27)
				)
			)
		)
		(property "Value" ""
			(at 0 0 180)
			(layer "F.Fab")
			(effects
				(font
					(size 1.27 1.27)
				)
			)
		)
		(duplicate_pad_numbers_are_jumpers no)
		(fp_line
			(start 0.7874 0.4064)
			(end -0.7874 0.4064)
			(stroke
				(width 0.1524)
				(type default)
			)
			(layer "F.SilkS")
		)
		(fp_line
			(start 0.7874 -0.4064)
			(end 0.7874 0.4064)
			(stroke
				(width 0.1524)
				(type default)
			)
			(layer "F.SilkS")
		)
		(fp_line
			(start -0.7874 0.4064)
			(end -0.7874 -0.4064)
			(stroke
				(width 0.1524)
				(type default)
			)
			(layer "F.SilkS")
		)
		(fp_line
			(start -0.7874 -0.4064)
			(end 0.7874 -0.4064)
			(stroke
				(width 0.1524)
				(type default)
			)
			(layer "F.SilkS")
		)
		(fp_line
			(start 0.67945 0.3048)
			(end 0.120396 0.3048)
			(stroke
				(width 0.1)
				(type default)
			)
			(layer "F.Fab")
		)
		(fp_line
			(start 0.67945 -0.3048)
			(end 0.67945 0.3048)
			(stroke
				(width 0.1)
				(type default)
			)
			(layer "F.Fab")
		)
		(fp_line
			(start 0.12065 -0.2794)
			(end 0.12065 -0.3048)
			(stroke
				(width 0.1)
				(type default)
			)
			(layer "F.Fab")
		)
		(fp_line
			(start 0.12065 -0.3048)
			(end 0.67945 -0.3048)
			(stroke
				(width 0.1)
				(type default)
			)
			(layer "F.Fab")
		)
		(fp_line
			(start 0.120396 0.3048)
			(end 0.120396 0.2794)
			(stroke
				(width 0.1)
				(type default)
			)
			(layer "F.Fab")
		)
		(fp_line
			(start 0.120396 0.2794)
			(end -0.12065 0.2794)
			(stroke
				(width 0.1)
				(type default)
			)
			(layer "F.Fab")
		)
		(fp_line
			(start -0.12065 0.3048)
			(end -0.67945 0.3048)
			(stroke
				(width 0.1)
				(type default)
			)
			(layer "F.Fab")
		)
		(fp_line
			(start -0.12065 0.2794)
			(end -0.12065 0.3048)
			(stroke
				(width 0.1)
				(type default)
			)
			(layer "F.Fab")
		)
		(fp_line
			(start -0.12065 -0.2794)
			(end 0.12065 -0.2794)
			(stroke
				(width 0.1)
				(type default)
			)
			(layer "F.Fab")
		)
		(fp_line
			(start -0.12065 -0.305054)
			(end -0.12065 -0.2794)
			(stroke
				(width 0.1)
				(type default)
			)
			(layer "F.Fab")
		)
		(fp_line
			(start -0.67945 0.3048)
			(end -0.67945 -0.305054)
			(stroke
				(width 0.1)
				(type default)
			)
			(layer "F.Fab")
		)
		(fp_line
			(start -0.67945 -0.305054)
			(end -0.12065 -0.305054)
			(stroke
				(width 0.1)
				(type default)
			)
			(layer "F.Fab")
		)
		(pad "1" smd circle
			(at -0.40005 0 180)
			(size 0 0)
			(layers "F.Cu" "F.Mask" "F.Paste")
			(net "ADC128_VREF")
		)
		(pad "2" smd circle
			(at 0.40005 0 180)
			(size 0 0)
			(layers "F.Cu" "F.Mask" "F.Paste")
			(net "GND")
		)
	)
	(footprint ""
		(layer "F.Cu")
		(at 463.562954 -93.396054)
		(property "Reference" "R3232"
			(at 0 0 0)
			(layer "F.SilkS")
			(hide yes)
			(effects
				(font
					(size 1.27 1.27)
				)
			)
		)
		(property "Value" ""
			(at 0 0 0)
			(layer "F.Fab")
			(effects
				(font
					(size 1.27 1.27)
				)
			)
		)
		(duplicate_pad_numbers_are_jumpers no)
		(fp_line
			(start -0.7874 -0.4064)
			(end 0.7874 -0.4064)
			(stroke
				(width 0.1524)
				(type default)
			)
			(layer "F.SilkS")
		)
		(fp_line
			(start -0.7874 0.4064)
			(end -0.7874 -0.4064)
			(stroke
				(width 0.1524)
				(type default)
			)
			(layer "F.SilkS")
		)
		(fp_line
			(start 0.7874 -0.4064)
			(end 0.7874 0.4064)
			(stroke
				(width 0.1524)
				(type default)
			)
			(layer "F.SilkS")
		)
		(fp_line
			(start 0.7874 0.4064)
			(end -0.7874 0.4064)
			(stroke
				(width 0.1524)
				(type default)
			)
			(layer "F.SilkS")
		)
		(fp_line
			(start -0.67945 -0.305054)
			(end -0.12065 -0.305054)
			(stroke
				(width 0.1)
				(type default)
			)
			(layer "F.Fab")
		)
		(fp_line
			(start -0.67945 0.3048)
			(end -0.67945 -0.305054)
			(stroke
				(width 0.1)
				(type default)
			)
			(layer "F.Fab")
		)
		(fp_line
			(start -0.12065 -0.305054)
			(end -0.12065 -0.2794)
			(stroke
				(width 0.1)
				(type default)
			)
			(layer "F.Fab")
		)
		(fp_line
			(start -0.12065 -0.2794)
			(end 0.12065 -0.2794)
			(stroke
				(width 0.1)
				(type default)
			)
			(layer "F.Fab")
		)
		(fp_line
			(start -0.12065 0.2794)
			(end -0.12065 0.3048)
			(stroke
				(width 0.1)
				(type default)
			)
			(layer "F.Fab")
		)
		(fp_line
			(start -0.12065 0.3048)
			(end -0.67945 0.3048)
			(stroke
				(width 0.1)
				(type default)
			)
			(layer "F.Fab")
		)
		(fp_line
			(start 0.120396 0.2794)
			(end -0.12065 0.2794)
			(stroke
				(width 0.1)
				(type default)
			)
			(layer "F.Fab")
		)
		(fp_line
			(start 0.120396 0.3048)
			(end 0.120396 0.2794)
			(stroke
				(width 0.1)
				(type default)
			)
			(layer "F.Fab")
		)
		(fp_line
			(start 0.12065 -0.3048)
			(end 0.67945 -0.3048)
			(stroke
				(width 0.1)
				(type default)
			)
			(layer "F.Fab")
		)
		(fp_line
			(start 0.12065 -0.2794)
			(end 0.12065 -0.3048)
			(stroke
				(width 0.1)
				(type default)
			)
			(layer "F.Fab")
		)
		(fp_line
			(start 0.67945 -0.3048)
			(end 0.67945 0.3048)
			(stroke
				(width 0.1)
				(type default)
			)
			(layer "F.Fab")
		)
		(fp_line
			(start 0.67945 0.3048)
			(end 0.120396 0.3048)
			(stroke
				(width 0.1)
				(type default)
			)
			(layer "F.Fab")
		)
		(pad "1" smd circle
			(at -0.40005 0)
			(size 0 0)
			(layers "F.Cu" "F.Mask" "F.Paste")
			(net "RST_HP_OCP_SFF_R_N")
		)
		(pad "2" smd circle
			(at 0.40005 0)
			(size 0 0)
			(layers "F.Cu" "F.Mask" "F.Paste")
			(net "GND")
		)
	)
)
